(kicad_pcb
	(version 20260206)
	(generator "pcbnew")
	(generator_version "10.0")
	(general
		(thickness 1.6)
		(legacy_teardrops no)
	)
	(paper "A4")
	(title_block
		(title "pdpb — Lightning_PDPB_BRD.brd")
		(comment 1 "Lightning (Wiwynn / Facebook NVMe JBOF) / footprints 663-669 of 1140")
	)
	(layers
		(0 "F.Cu" signal "TOP")
		(4 "In1.Cu" signal "L2GND")
		(6 "In2.Cu" signal "L3")
		(8 "In3.Cu" signal "L4VCC")
		(10 "In4.Cu" signal "L5VCC")
		(12 "In5.Cu" signal "L6")
		(14 "In6.Cu" signal "L7GND")
		(2 "B.Cu" signal "BOTTOM")
		(9 "F.Adhes" user "F.Adhesive")
		(11 "B.Adhes" user "B.Adhesive")
		(13 "F.Paste" user "Package Geometry/Pastemask Top")
		(15 "B.Paste" user "Package Geometry/Pastemask Bottom")
		(5 "F.SilkS" user "Ref Des/Silkscreen Top")
		(7 "B.SilkS" user "Ref Des/Silkscreen Bottom")
		(1 "F.Mask" user "Board Geometry/Soldermask Top")
		(3 "B.Mask" user "Board Geometry/Soldermask Bottom")
		(17 "Dwgs.User" user "User.Drawings")
		(19 "Cmts.User" user "User.Comments")
		(21 "Eco1.User" user "User.Eco1")
		(23 "Eco2.User" user "User.Eco2")
		(25 "Edge.Cuts" user "Board Geometry/Outline")
		(27 "Margin" user)
		(31 "F.CrtYd" user "Package Geometry/Place Bound Top")
		(29 "B.CrtYd" user "Package Geometry/Place Bound Bottom")
		(35 "F.Fab" user "Ref Des/Assembly Top")
		(33 "B.Fab" user "Ref Des/Assembly Bottom")
	)
	(footprint ""
		(layer "F.Cu")
		(at 50.8 -7.747 180)
		(property "Reference" "R9774"
			(at 0 0 180)
			(layer "F.SilkS")
			(hide yes)
			(effects
				(font
					(size 1.27 1.27)
				)
			)
		)
		(property "Value" "4K7R2J-2-GP"
			(at 0.064008 -3.993896 180)
			(unlocked yes)
			(layer "F.Fab")
			(hide yes)
			(effects
				(font
					(size 1.016 1.016)
					(thickness 0.1524)
				)
			)
		)
		(property "Device Type" "R402H16"
			(at 0.064008 -5.517896 180)
			(unlocked yes)
			(layer "F.Fab")
			(hide yes)
			(effects
				(font
					(size 1.016 1.016)
					(thickness 0.1524)
				)
			)
		)
		(duplicate_pad_numbers_are_jumpers no)
		(fp_line
			(start 0.508 -0.9398)
			(end -0.508 -0.9398)
			(stroke
				(width 0.1524)
				(type default)
			)
			(layer "F.SilkS")
		)
		(fp_line
			(start -0.508 -0.9398)
			(end -0.508 0.9398)
			(stroke
				(width 0.1524)
				(type default)
			)
			(layer "F.SilkS")
		)
		(fp_rect
			(start -0.508 0.9398)
			(end 0.508 -0.9398)
			(stroke
				(width 0)
				(type default)
			)
			(fill no)
			(layer "F.CrtYd")
		)
		(fp_rect
			(start -0.508 0.9398)
			(end 0.508 -0.9398)
			(stroke
				(width 0)
				(type default)
			)
			(fill no)
			(layer "F.Fab")
		)
		(pad "1" smd custom
			(at 0 -0.4445 180)
			(size 0.1397 0.1397)
			(layers "F.Cu" "F.Mask" "F.Paste")
			(net "SSD14_PWREN")
			(options
				(clearance outline)
				(anchor circle)
			)
			(primitives
				(gr_poly
					(pts
						(arc
							(start -0.1778 -0.2794)
							(mid -0.249642 -0.249642)
							(end -0.2794 -0.1778)
						)
						(arc
							(start -0.2794 0.1778)
							(mid -0.249642 0.249642)
							(end -0.1778 0.2794)
						)
						(arc
							(start 0.1778 0.2794)
							(mid 0.249642 0.249642)
							(end 0.2794 0.1778)
						)
						(arc
							(start 0.2794 -0.1778)
							(mid 0.249642 -0.249642)
							(end 0.1778 -0.2794)
						)
					)
					(width 0)
					(fill yes)
				)
			)
		)
		(pad "2" smd custom
			(at 0 0.4445 180)
			(size 0.1397 0.1397)
			(layers "F.Cu" "F.Mask" "F.Paste")
			(net "GND")
			(options
				(clearance outline)
				(anchor circle)
			)
			(primitives
				(gr_poly
					(pts
						(arc
							(start -0.1778 -0.2794)
							(mid -0.249642 -0.249642)
							(end -0.2794 -0.1778)
						)
						(arc
							(start -0.2794 0.1778)
							(mid -0.249642 0.249642)
							(end -0.1778 0.2794)
						)
						(arc
							(start 0.1778 0.2794)
							(mid 0.249642 0.249642)
							(end 0.2794 0.1778)
						)
						(arc
							(start 0.2794 -0.1778)
							(mid 0.249642 -0.249642)
							(end 0.1778 -0.2794)
						)
					)
					(width 0)
					(fill yes)
				)
			)
		)
	)
	(footprint ""
		(layer "F.Cu")
		(at 222.123 -245.104158)
		(property "Reference" "Q40"
			(at 0 0 0)
			(layer "F.SilkS")
			(hide yes)
			(effects
				(font
					(size 1.27 1.27)
				)
			)
		)
		(property "Value" "2N7002A-7-GP"
			(at 0.127 -8.9662 0)
			(unlocked yes)
			(layer "F.Fab")
			(hide yes)
			(effects
				(font
					(size 1.016 1.016)
					(thickness 0.1524)
				)
			)
		)
		(property "Device Type" "SOT23DGS2D4H48"
			(at 0.127 -10.4902 0)
			(unlocked yes)
			(layer "F.Fab")
			(hide yes)
			(effects
				(font
					(size 1.016 1.016)
					(thickness 0.1524)
				)
			)
		)
		(duplicate_pad_numbers_are_jumpers no)
		(fp_line
			(start -1.651 -1.778)
			(end -1.651 1.778)
			(stroke
				(width 0.1524)
				(type default)
			)
			(layer "F.SilkS")
		)
		(fp_line
			(start -1.651 1.778)
			(end 1.651 1.778)
			(stroke
				(width 0.1524)
				(type default)
			)
			(layer "F.SilkS")
		)
		(fp_line
			(start 1.651 -1.778)
			(end -1.651 -1.778)
			(stroke
				(width 0.1524)
				(type default)
			)
			(layer "F.SilkS")
		)
		(fp_line
			(start 1.651 1.778)
			(end 1.651 -1.778)
			(stroke
				(width 0.1524)
				(type default)
			)
			(layer "F.SilkS")
		)
		(fp_poly
			(pts
				(xy -1.778 1.8796) (xy -1.778 -1.8796) (xy 1.778 -1.8796) (xy 1.778 1.8796)
			)
			(stroke
				(width 0)
				(type default)
			)
			(fill no)
			(layer "F.CrtYd")
		)
		(fp_poly
			(pts
				(xy -1.778 1.8796) (xy -1.778 -1.8796) (xy 1.778 -1.8796) (xy 1.778 1.8796)
			)
			(stroke
				(width 0)
				(type default)
			)
			(fill no)
			(layer "F.Fab")
		)
		(pad "D" smd custom
			(at 0 -0.9525)
			(size 0.1905 0.1905)
			(layers "F.Cu" "F.Mask" "F.Paste")
			(net "ATTN_LED_DR2_MOS_N")
			(options
				(clearance outline)
				(anchor circle)
			)
			(primitives
				(gr_poly
					(pts
						(arc
							(start -0.1778 0.5715)
							(mid -0.321484 0.511984)
							(end -0.381 0.3683)
						)
						(arc
							(start -0.381 -0.3683)
							(mid -0.321484 -0.511984)
							(end -0.1778 -0.5715)
						)
						(arc
							(start 0.1778 -0.5715)
							(mid 0.321484 -0.511984)
							(end 0.381 -0.3683)
						)
						(arc
							(start 0.381 0.3683)
							(mid 0.321484 0.511984)
							(end 0.1778 0.5715)
						)
					)
					(width 0)
					(fill yes)
				)
			)
		)
		(pad "G" smd custom
			(at -0.98425 0.9525)
			(size 0.1905 0.1905)
			(layers "F.Cu" "F.Mask" "F.Paste")
			(net "SSD2_CLK0_OE_MOS_N")
			(options
				(clearance outline)
				(anchor circle)
			)
			(primitives
				(gr_poly
					(pts
						(arc
							(start -0.1778 0.5715)
							(mid -0.321484 0.511984)
							(end -0.381 0.3683)
						)
						(arc
							(start -0.381 -0.3683)
							(mid -0.321484 -0.511984)
							(end -0.1778 -0.5715)
						)
						(arc
							(start 0.1778 -0.5715)
							(mid 0.321484 -0.511984)
							(end 0.381 -0.3683)
						)
						(arc
							(start 0.381 0.3683)
							(mid 0.321484 0.511984)
							(end 0.1778 0.5715)
						)
					)
					(width 0)
					(fill yes)
				)
			)
		)
		(pad "S" smd custom
			(at 0.98425 0.9525)
			(size 0.1905 0.1905)
			(layers "F.Cu" "F.Mask" "F.Paste")
			(net "ATTN_LED_DR2_R")
			(options
				(clearance outline)
				(anchor circle)
			)
			(primitives
				(gr_poly
					(pts
						(arc
							(start -0.1778 0.5715)
							(mid -0.321484 0.511984)
							(end -0.381 0.3683)
						)
						(arc
							(start -0.381 -0.3683)
							(mid -0.321484 -0.511984)
							(end -0.1778 -0.5715)
						)
						(arc
							(start 0.1778 -0.5715)
							(mid 0.321484 -0.511984)
							(end 0.381 -0.3683)
						)
						(arc
							(start 0.381 0.3683)
							(mid 0.321484 0.511984)
							(end 0.1778 0.5715)
						)
					)
					(width 0)
					(fill yes)
				)
			)
		)
	)
	(footprint ""
		(layer "F.Cu")
		(at 87.503 -306.324 180)
		(property "Reference" "C8912"
			(at 0 0 180)
			(layer "F.SilkS")
			(hide yes)
			(effects
				(font
					(size 1.27 1.27)
				)
			)
		)
		(property "Value" "SCD1U16V2KX-3GP"
			(at 1.1811 -2.7051 180)
			(unlocked yes)
			(layer "F.Fab")
			(hide yes)
			(effects
				(font
					(size 1.016 1.016)
					(thickness 0.1524)
				)
			)
		)
		(property "Device Type" "C402H22"
			(at 1.1811 -4.2291 180)
			(unlocked yes)
			(layer "F.Fab")
			(hide yes)
			(effects
				(font
					(size 1.016 1.016)
					(thickness 0.1524)
				)
			)
		)
		(duplicate_pad_numbers_are_jumpers no)
		(fp_rect
			(start -0.4318 0.9525)
			(end 0.4318 -0.9525)
			(stroke
				(width 0)
				(type default)
			)
			(fill no)
			(layer "F.CrtYd")
		)
		(fp_rect
			(start -0.4318 0.9525)
			(end 0.4318 -0.9525)
			(stroke
				(width 0)
				(type default)
			)
			(fill no)
			(layer "F.Fab")
		)
		(pad "1" smd custom
			(at 0 -0.4445 180)
			(size 0.1524 0.1524)
			(layers "F.Cu" "F.Mask" "F.Paste")
			(net "VDDR_2")
			(options
				(clearance outline)
				(anchor circle)
			)
			(primitives
				(gr_poly
					(pts
						(arc
							(start 0.3048 -0.2032)
							(mid 0.275042 -0.275042)
							(end 0.2032 -0.3048)
						)
						(arc
							(start -0.2032 -0.3048)
							(mid -0.275042 -0.275042)
							(end -0.3048 -0.2032)
						)
						(arc
							(start -0.3048 0.2032)
							(mid -0.275042 0.275042)
							(end -0.2032 0.3048)
						)
						(arc
							(start 0.2032 0.3048)
							(mid 0.275042 0.275042)
							(end 0.3048 0.2032)
						)
					)
					(width 0)
					(fill yes)
				)
			)
		)
		(pad "2" smd custom
			(at 0 0.4445 180)
			(size 0.1524 0.1524)
			(layers "F.Cu" "F.Mask" "F.Paste")
			(net "GND")
			(options
				(clearance outline)
				(anchor circle)
			)
			(primitives
				(gr_poly
					(pts
						(arc
							(start 0.3048 -0.2032)
							(mid 0.275042 -0.275042)
							(end 0.2032 -0.3048)
						)
						(arc
							(start -0.2032 -0.3048)
							(mid -0.275042 -0.275042)
							(end -0.3048 -0.2032)
						)
						(arc
							(start -0.3048 0.2032)
							(mid -0.275042 0.275042)
							(end -0.2032 0.3048)
						)
						(arc
							(start 0.2032 0.3048)
							(mid 0.275042 0.275042)
							(end 0.3048 0.2032)
						)
					)
					(width 0)
					(fill yes)
				)
			)
		)
	)
	(footprint ""
		(layer "F.Cu")
		(at 44.677076 -35.474402)
		(property "Reference" "C9527"
			(at 0 0 0)
			(layer "F.SilkS")
			(hide yes)
			(effects
				(font
					(size 1.27 1.27)
				)
			)
		)
		(property "Value" "SCD1U16V2KX-3GP"
			(at 1.1811 -2.7051 0)
			(unlocked yes)
			(layer "F.Fab")
			(hide yes)
			(effects
				(font
					(size 1.016 1.016)
					(thickness 0.1524)
				)
			)
		)
		(property "Device Type" "C402H22"
			(at 1.1811 -4.2291 0)
			(unlocked yes)
			(layer "F.Fab")
			(hide yes)
			(effects
				(font
					(size 1.016 1.016)
					(thickness 0.1524)
				)
			)
		)
		(duplicate_pad_numbers_are_jumpers no)
		(fp_rect
			(start -0.4318 0.9525)
			(end 0.4318 -0.9525)
			(stroke
				(width 0)
				(type default)
			)
			(fill no)
			(layer "F.CrtYd")
		)
		(fp_rect
			(start -0.4318 0.9525)
			(end 0.4318 -0.9525)
			(stroke
				(width 0)
				(type default)
			)
			(fill no)
			(layer "F.Fab")
		)
		(pad "1" smd custom
			(at 0 -0.4445)
			(size 0.1524 0.1524)
			(layers "F.Cu" "F.Mask" "F.Paste")
			(net "P3V3")
			(options
				(clearance outline)
				(anchor circle)
			)
			(primitives
				(gr_poly
					(pts
						(arc
							(start 0.3048 -0.2032)
							(mid 0.275042 -0.275042)
							(end 0.2032 -0.3048)
						)
						(arc
							(start -0.2032 -0.3048)
							(mid -0.275042 -0.275042)
							(end -0.3048 -0.2032)
						)
						(arc
							(start -0.3048 0.2032)
							(mid -0.275042 0.275042)
							(end -0.2032 0.3048)
						)
						(arc
							(start 0.2032 0.3048)
							(mid 0.275042 0.275042)
							(end 0.3048 0.2032)
						)
					)
					(width 0)
					(fill yes)
				)
			)
		)
		(pad "2" smd custom
			(at 0 0.4445)
			(size 0.1524 0.1524)
			(layers "F.Cu" "F.Mask" "F.Paste")
			(net "GND")
			(options
				(clearance outline)
				(anchor circle)
			)
			(primitives
				(gr_poly
					(pts
						(arc
							(start 0.3048 -0.2032)
							(mid 0.275042 -0.275042)
							(end 0.2032 -0.3048)
						)
						(arc
							(start -0.2032 -0.3048)
							(mid -0.275042 -0.275042)
							(end -0.3048 -0.2032)
						)
						(arc
							(start -0.3048 0.2032)
							(mid -0.275042 0.275042)
							(end -0.2032 0.3048)
						)
						(arc
							(start 0.2032 0.3048)
							(mid 0.275042 0.275042)
							(end 0.3048 0.2032)
						)
					)
					(width 0)
					(fill yes)
				)
			)
		)
	)
	(footprint ""
		(layer "F.Cu")
		(at 98.679 -291.719 180)
		(property "Reference" "R9593"
			(at 0 0 180)
			(layer "F.SilkS")
			(hide yes)
			(effects
				(font
					(size 1.27 1.27)
				)
			)
		)
		(property "Value" "10R2F-L-GP"
			(at 0.064008 -3.993896 180)
			(unlocked yes)
			(layer "F.Fab")
			(hide yes)
			(effects
				(font
					(size 1.016 1.016)
					(thickness 0.1524)
				)
			)
		)
		(property "Device Type" "R402H14"
			(at 0.064008 -5.517896 180)
			(unlocked yes)
			(layer "F.Fab")
			(hide yes)
			(effects
				(font
					(size 1.016 1.016)
					(thickness 0.1524)
				)
			)
		)
		(duplicate_pad_numbers_are_jumpers no)
		(fp_line
			(start 0.508 -0.9398)
			(end -0.508 -0.9398)
			(stroke
				(width 0.1524)
				(type default)
			)
			(layer "F.SilkS")
		)
		(fp_line
			(start -0.508 -0.9398)
			(end -0.508 0.9398)
			(stroke
				(width 0.1524)
				(type default)
			)
			(layer "F.SilkS")
		)
		(fp_rect
			(start -0.508 0.9398)
			(end 0.508 -0.9398)
			(stroke
				(width 0)
				(type default)
			)
			(fill no)
			(layer "F.CrtYd")
		)
		(fp_rect
			(start -0.508 0.9398)
			(end 0.508 -0.9398)
			(stroke
				(width 0)
				(type default)
			)
			(fill no)
			(layer "F.Fab")
		)
		(pad "1" smd custom
			(at 0 -0.4445 180)
			(size 0.1397 0.1397)
			(layers "F.Cu" "F.Mask" "F.Paste")
			(net "SSD2_CLK0_OE_N")
			(options
				(clearance outline)
				(anchor circle)
			)
			(primitives
				(gr_poly
					(pts
						(arc
							(start -0.1778 -0.2794)
							(mid -0.249642 -0.249642)
							(end -0.2794 -0.1778)
						)
						(arc
							(start -0.2794 0.1778)
							(mid -0.249642 0.249642)
							(end -0.1778 0.2794)
						)
						(arc
							(start 0.1778 0.2794)
							(mid 0.249642 0.249642)
							(end 0.2794 0.1778)
						)
						(arc
							(start 0.2794 -0.1778)
							(mid 0.249642 -0.249642)
							(end 0.1778 -0.2794)
						)
					)
					(width 0)
					(fill yes)
				)
			)
		)
		(pad "2" smd custom
			(at 0 0.4445 180)
			(size 0.1397 0.1397)
			(layers "F.Cu" "F.Mask" "F.Paste")
			(net "SSD2_CLK0_OE_R_N")
			(options
				(clearance outline)
				(anchor circle)
			)
			(primitives
				(gr_poly
					(pts
						(arc
							(start -0.1778 -0.2794)
							(mid -0.249642 -0.249642)
							(end -0.2794 -0.1778)
						)
						(arc
							(start -0.2794 0.1778)
							(mid -0.249642 0.249642)
							(end -0.1778 0.2794)
						)
						(arc
							(start 0.1778 0.2794)
							(mid 0.249642 0.249642)
							(end 0.2794 0.1778)
						)
						(arc
							(start 0.2794 -0.1778)
							(mid 0.249642 -0.249642)
							(end 0.1778 -0.2794)
						)
					)
					(width 0)
					(fill yes)
				)
			)
		)
	)
	(footprint ""
		(layer "F.Cu")
		(at 217.4748 -84.455 180)
		(property "Reference" "SR1100"
			(at 0 0 180)
			(layer "F.SilkS")
			(hide yes)
			(effects
				(font
					(size 1.27 1.27)
				)
			)
		)
		(property "Value" "4K7R2F-GP"
			(at 0.064008 -3.993896 180)
			(unlocked yes)
			(layer "F.Fab")
			(hide yes)
			(effects
				(font
					(size 1.016 1.016)
					(thickness 0.1524)
				)
			)
		)
		(property "Device Type" "R402H16"
			(at 0.064008 -5.517896 180)
			(unlocked yes)
			(layer "F.Fab")
			(hide yes)
			(effects
				(font
					(size 1.016 1.016)
					(thickness 0.1524)
				)
			)
		)
		(duplicate_pad_numbers_are_jumpers no)
		(fp_line
			(start 0.508 -0.9398)
			(end -0.508 -0.9398)
			(stroke
				(width 0.1524)
				(type default)
			)
			(layer "F.SilkS")
		)
		(fp_line
			(start -0.508 -0.9398)
			(end -0.508 0.9398)
			(stroke
				(width 0.1524)
				(type default)
			)
			(layer "F.SilkS")
		)
		(fp_rect
			(start -0.508 0.9398)
			(end 0.508 -0.9398)
			(stroke
				(width 0)
				(type default)
			)
			(fill no)
			(layer "F.CrtYd")
		)
		(fp_rect
			(start -0.508 0.9398)
			(end 0.508 -0.9398)
			(stroke
				(width 0)
				(type default)
			)
			(fill no)
			(layer "F.Fab")
		)
		(pad "1" smd custom
			(at 0 -0.4445 180)
			(size 0.1397 0.1397)
			(layers "F.Cu" "F.Mask" "F.Paste")
			(net "DUALPORTEN#4")
			(options
				(clearance outline)
				(anchor circle)
			)
			(primitives
				(gr_poly
					(pts
						(arc
							(start -0.1778 -0.2794)
							(mid -0.249642 -0.249642)
							(end -0.2794 -0.1778)
						)
						(arc
							(start -0.2794 0.1778)
							(mid -0.249642 0.249642)
							(end -0.1778 0.2794)
						)
						(arc
							(start 0.1778 0.2794)
							(mid 0.249642 0.249642)
							(end 0.2794 0.1778)
						)
						(arc
							(start 0.2794 -0.1778)
							(mid 0.249642 -0.249642)
							(end 0.1778 -0.2794)
						)
					)
					(width 0)
					(fill yes)
				)
			)
		)
		(pad "2" smd custom
			(at 0 0.4445 180)
			(size 0.1397 0.1397)
			(layers "F.Cu" "F.Mask" "F.Paste")
			(net "GND")
			(options
				(clearance outline)
				(anchor circle)
			)
			(primitives
				(gr_poly
					(pts
						(arc
							(start -0.1778 -0.2794)
							(mid -0.249642 -0.249642)
							(end -0.2794 -0.1778)
						)
						(arc
							(start -0.2794 0.1778)
							(mid -0.249642 0.249642)
							(end -0.1778 0.2794)
						)
						(arc
							(start 0.1778 0.2794)
							(mid 0.249642 0.249642)
							(end 0.2794 0.1778)
						)
						(arc
							(start 0.2794 -0.1778)
							(mid 0.249642 -0.249642)
							(end 0.1778 -0.2794)
						)
					)
					(width 0)
					(fill yes)
				)
			)
		)
	)
	(footprint ""
		(layer "F.Cu")
		(at 88.519 -18.669 180)
		(property "Reference" "R364"
			(at 0 0 180)
			(layer "F.SilkS")
			(hide yes)
			(effects
				(font
					(size 1.27 1.27)
				)
			)
		)
		(property "Value" "4K7R2F-GP"
			(at 0.064008 -3.993896 180)
			(unlocked yes)
			(layer "F.Fab")
			(hide yes)
			(effects
				(font
					(size 1.016 1.016)
					(thickness 0.1524)
				)
			)
		)
		(property "Device Type" "R402H16"
			(at 0.064008 -5.517896 180)
			(unlocked yes)
			(layer "F.Fab")
			(hide yes)
			(effects
				(font
					(size 1.016 1.016)
					(thickness 0.1524)
				)
			)
		)
		(duplicate_pad_numbers_are_jumpers no)
		(fp_line
			(start 0.508 -0.9398)
			(end -0.508 -0.9398)
			(stroke
				(width 0.1524)
				(type default)
			)
			(layer "F.SilkS")
		)
		(fp_line
			(start -0.508 -0.9398)
			(end -0.508 0.9398)
			(stroke
				(width 0.1524)
				(type default)
			)
			(layer "F.SilkS")
		)
		(fp_rect
			(start -0.508 0.9398)
			(end 0.508 -0.9398)
			(stroke
				(width 0)
				(type default)
			)
			(fill no)
			(layer "F.CrtYd")
		)
		(fp_rect
			(start -0.508 0.9398)
			(end 0.508 -0.9398)
			(stroke
				(width 0)
				(type default)
			)
			(fill no)
			(layer "F.Fab")
		)
		(pad "1" smd custom
			(at 0 -0.4445 180)
			(size 0.1397 0.1397)
			(layers "F.Cu" "F.Mask" "F.Paste")
			(net "P3V3")
			(options
				(clearance outline)
				(anchor circle)
			)
			(primitives
				(gr_poly
					(pts
						(arc
							(start -0.1778 -0.2794)
							(mid -0.249642 -0.249642)
							(end -0.2794 -0.1778)
						)
						(arc
							(start -0.2794 0.1778)
							(mid -0.249642 0.249642)
							(end -0.1778 0.2794)
						)
						(arc
							(start 0.1778 0.2794)
							(mid 0.249642 0.249642)
							(end 0.2794 0.1778)
						)
						(arc
							(start 0.2794 -0.1778)
							(mid 0.249642 -0.249642)
							(end 0.1778 -0.2794)
						)
					)
					(width 0)
					(fill yes)
				)
			)
		)
		(pad "2" smd custom
			(at 0 0.4445 180)
			(size 0.1397 0.1397)
			(layers "F.Cu" "F.Mask" "F.Paste")
			(net "VOL_SEN_ADDR")
			(options
				(clearance outline)
				(anchor circle)
			)
			(primitives
				(gr_poly
					(pts
						(arc
							(start -0.1778 -0.2794)
							(mid -0.249642 -0.249642)
							(end -0.2794 -0.1778)
						)
						(arc
							(start -0.2794 0.1778)
							(mid -0.249642 0.249642)
							(end -0.1778 0.2794)
						)
						(arc
							(start 0.1778 0.2794)
							(mid 0.249642 0.249642)
							(end 0.2794 0.1778)
						)
						(arc
							(start 0.2794 -0.1778)
							(mid 0.249642 -0.249642)
							(end 0.1778 -0.2794)
						)
					)
					(width 0)
					(fill yes)
				)
			)
		)
	)
)
